(kicad_pcb
	(version 20260206)
	(generator "pcbnew")
	(generator_version "10.0")
	(general
		(thickness 1.6)
		(legacy_teardrops no)
	)
	(paper "A4")
	(title_block
		(title "peb — Lightning_PEB_BRD.brd")
		(comment 1 "Lightning (Wiwynn / Facebook NVMe JBOF) / footprints 1389-1396 of 2563")
	)
	(layers
		(0 "F.Cu" signal "TOP")
		(4 "In1.Cu" signal "L2GND")
		(6 "In2.Cu" signal "L3")
		(8 "In3.Cu" signal "L4VCC")
		(10 "In4.Cu" signal "L5VCC")
		(12 "In5.Cu" signal "L6")
		(14 "In6.Cu" signal "L7GND")
		(2 "B.Cu" signal "BOTTOM")
		(9 "F.Adhes" user "F.Adhesive")
		(11 "B.Adhes" user "B.Adhesive")
		(13 "F.Paste" user "Package Geometry/Pastemask Top")
		(15 "B.Paste" user "Package Geometry/Pastemask Bottom")
		(5 "F.SilkS" user "Ref Des/Silkscreen Top")
		(7 "B.SilkS" user "Ref Des/Silkscreen Bottom")
		(1 "F.Mask" user "Board Geometry/Soldermask Top")
		(3 "B.Mask" user "Board Geometry/Soldermask Bottom")
		(17 "Dwgs.User" user "User.Drawings")
		(19 "Cmts.User" user "User.Comments")
		(21 "Eco1.User" user "User.Eco1")
		(23 "Eco2.User" user "User.Eco2")
		(25 "Edge.Cuts" user "Board Geometry/Outline")
		(27 "Margin" user)
		(31 "F.CrtYd" user "Package Geometry/Place Bound Top")
		(29 "B.CrtYd" user "Package Geometry/Place Bound Bottom")
		(35 "F.Fab" user "Ref Des/Assembly Top")
		(33 "B.Fab" user "Ref Des/Assembly Bottom")
	)
	(footprint ""
		(layer "F.Cu")
		(at 145.796 -89.535 180)
		(property "Reference" "PC88"
			(at 0 0 180)
			(layer "F.SilkS")
			(hide yes)
			(effects
				(font
					(size 1.27 1.27)
				)
			)
		)
		(property "Value" "SC22U6D3V5MX-5-GP"
			(at -0.0762 -6.1214 180)
			(unlocked yes)
			(layer "F.Fab")
			(hide yes)
			(effects
				(font
					(size 1.016 1.016)
					(thickness 0.1524)
				)
			)
		)
		(property "Device Type" "C805H56"
			(at -0.0762 -8.1534 180)
			(unlocked yes)
			(layer "F.Fab")
			(hide yes)
			(effects
				(font
					(size 1.016 1.016)
					(thickness 0.1524)
				)
			)
		)
		(duplicate_pad_numbers_are_jumpers no)
		(fp_line
			(start 0.635 0)
			(end -0.635 0)
			(stroke
				(width 0.508)
				(type default)
			)
			(layer "F.SilkS")
		)
		(fp_rect
			(start -0.9652 1.778)
			(end 0.9652 -1.778)
			(stroke
				(width 0)
				(type default)
			)
			(fill no)
			(layer "F.CrtYd")
		)
		(fp_poly
			(pts
				(xy -0.9652 -1.778) (xy 0.9652 -1.778) (xy 0.9652 1.778) (xy -0.9652 1.778)
			)
			(stroke
				(width 0)
				(type default)
			)
			(fill no)
			(layer "F.Fab")
		)
		(pad "1" smd rect
			(at 0 -0.9652 180)
			(size 1.397 1.143)
			(layers "F.Cu" "F.Mask" "F.Paste")
			(net "P1V8_PWR")
		)
		(pad "2" smd rect
			(at 0 0.9652 180)
			(size 1.397 1.143)
			(layers "F.Cu" "F.Mask" "F.Paste")
			(net "GND")
		)
	)
	(footprint ""
		(layer "F.Cu")
		(at 202.0062 -4.0894 180)
		(property "Reference" "JP10"
			(at 0 0 180)
			(layer "F.SilkS")
			(hide yes)
			(effects
				(font
					(size 1.27 1.27)
				)
			)
		)
		(property "Value" "PIN-CON3-S-GP"
			(at -5.588 -5.3086 180)
			(unlocked yes)
			(layer "F.Fab")
			(hide yes)
			(effects
				(font
					(size 1.016 1.016)
					(thickness 0.1524)
				)
			)
		)
		(property "Device Type" "21S-91-03GB01"
			(at -5.588 -6.8326 180)
			(unlocked yes)
			(layer "F.Fab")
			(hide yes)
			(effects
				(font
					(size 1.016 1.016)
					(thickness 0.1524)
				)
			)
		)
		(duplicate_pad_numbers_are_jumpers no)
		(fp_line
			(start 3.8862 1.4986)
			(end 3.8862 -1.4986)
			(stroke
				(width 0.1524)
				(type default)
			)
			(layer "F.SilkS")
		)
		(fp_line
			(start 3.8862 -1.4986)
			(end -3.8862 -1.4986)
			(stroke
				(width 0.1524)
				(type default)
			)
			(layer "F.SilkS")
		)
		(fp_line
			(start -3.8862 1.4986)
			(end 3.8862 1.4986)
			(stroke
				(width 0.1524)
				(type default)
			)
			(layer "F.SilkS")
		)
		(fp_line
			(start -3.8862 -1.4986)
			(end -3.8862 1.4986)
			(stroke
				(width 0.1524)
				(type default)
			)
			(layer "F.SilkS")
		)
		(fp_line
			(start -4.0132 -0.3556)
			(end -4.0132 -1.6256)
			(stroke
				(width 0.4064)
				(type default)
			)
			(layer "F.SilkS")
		)
		(fp_line
			(start -4.0132 -1.6256)
			(end -2.7432 -1.6256)
			(stroke
				(width 0.4064)
				(type default)
			)
			(layer "F.SilkS")
		)
		(fp_circle
			(center 2.54 0)
			(end 1.4732 0)
			(stroke
				(width 0.3048)
				(type default)
			)
			(fill no)
			(layer "F.SilkS")
		)
		(fp_circle
			(center 0 0)
			(end -1.0668 0)
			(stroke
				(width 0.3048)
				(type default)
			)
			(fill no)
			(layer "F.SilkS")
		)
		(fp_circle
			(center -2.54 0)
			(end -3.6068 0)
			(stroke
				(width 0.3048)
				(type default)
			)
			(fill no)
			(layer "F.SilkS")
		)
		(fp_rect
			(start -3.6322 1.2446)
			(end 3.6322 -1.2446)
			(stroke
				(width 0)
				(type default)
			)
			(fill no)
			(layer "F.CrtYd")
		)
		(fp_poly
			(pts
				(xy 4.1402 -1.2446) (xy -3.6322 -1.2446) (xy -3.6322 1.2446) (xy 3.6322 1.2446) (xy 3.6322 -1.2319)
				(xy 4.1402 -1.2319) (xy 4.1402 1.7526) (xy -4.1402 1.7526) (xy -4.1402 -1.7526) (xy 4.1402 -1.7526)
			)
			(stroke
				(width 0)
				(type default)
			)
			(fill no)
			(layer "F.CrtYd")
		)
		(fp_rect
			(start -4.1402 1.7526)
			(end 4.1402 -1.7526)
			(stroke
				(width 0)
				(type default)
			)
			(fill no)
			(layer "F.Fab")
		)
		(pad "1" thru_hole circle
			(at -2.54 0 180)
			(size 1.4224 1.4224)
			(drill 1.016)
			(layers "*.Cu" "*.Mask")
			(remove_unused_layers no)
			(net "BOOT_RECOVERY_1")
			(clearance 0.1524)
			(thermal_gap 0.1524)
		)
		(pad "2" thru_hole circle
			(at 0 0 180)
			(size 1.4224 1.4224)
			(drill 1.016)
			(layers "*.Cu" "*.Mask")
			(remove_unused_layers no)
			(net "BOOT_RECOVERY#_R")
			(clearance 0.1524)
			(thermal_gap 0.1524)
		)
		(pad "3" thru_hole circle
			(at 2.54 0 180)
			(size 1.4224 1.4224)
			(drill 1.016)
			(layers "*.Cu" "*.Mask")
			(remove_unused_layers no)
			(net "BOOT_RECOVERY_0")
			(clearance 0.1524)
			(thermal_gap 0.1524)
		)
	)
	(footprint ""
		(layer "F.Cu")
		(at 148.463 -33.528)
		(property "Reference" "C392"
			(at 0 0 0)
			(layer "F.SilkS")
			(hide yes)
			(effects
				(font
					(size 1.27 1.27)
				)
			)
		)
		(property "Value" "SCD22U10V2KX-1GP"
			(at 1.1811 -2.7051 0)
			(unlocked yes)
			(layer "F.Fab")
			(hide yes)
			(effects
				(font
					(size 1.016 1.016)
					(thickness 0.1524)
				)
			)
		)
		(property "Device Type" "C402H22"
			(at 1.1811 -4.2291 0)
			(unlocked yes)
			(layer "F.Fab")
			(hide yes)
			(effects
				(font
					(size 1.016 1.016)
					(thickness 0.1524)
				)
			)
		)
		(duplicate_pad_numbers_are_jumpers no)
		(fp_rect
			(start -0.4318 0.9525)
			(end 0.4318 -0.9525)
			(stroke
				(width 0)
				(type default)
			)
			(fill no)
			(layer "F.CrtYd")
		)
		(fp_rect
			(start -0.4318 0.9525)
			(end 0.4318 -0.9525)
			(stroke
				(width 0)
				(type default)
			)
			(fill no)
			(layer "F.Fab")
		)
		(pad "1" smd custom
			(at 0 -0.4445)
			(size 0.1524 0.1524)
			(layers "F.Cu" "F.Mask" "F.Paste")
			(net "PCIE_TX_CAP_P86")
			(options
				(clearance outline)
				(anchor circle)
			)
			(primitives
				(gr_poly
					(pts
						(arc
							(start 0.3048 -0.2032)
							(mid 0.275042 -0.275042)
							(end 0.2032 -0.3048)
						)
						(arc
							(start -0.2032 -0.3048)
							(mid -0.275042 -0.275042)
							(end -0.3048 -0.2032)
						)
						(arc
							(start -0.3048 0.2032)
							(mid -0.275042 0.275042)
							(end -0.2032 0.3048)
						)
						(arc
							(start 0.2032 0.3048)
							(mid 0.275042 0.275042)
							(end 0.3048 0.2032)
						)
					)
					(width 0)
					(fill yes)
				)
			)
		)
		(pad "2" smd custom
			(at 0 0.4445)
			(size 0.1524 0.1524)
			(layers "F.Cu" "F.Mask" "F.Paste")
			(net "PCIE_TX_P86")
			(options
				(clearance outline)
				(anchor circle)
			)
			(primitives
				(gr_poly
					(pts
						(arc
							(start 0.3048 -0.2032)
							(mid 0.275042 -0.275042)
							(end 0.2032 -0.3048)
						)
						(arc
							(start -0.2032 -0.3048)
							(mid -0.275042 -0.275042)
							(end -0.3048 -0.2032)
						)
						(arc
							(start -0.3048 0.2032)
							(mid -0.275042 0.275042)
							(end -0.2032 0.3048)
						)
						(arc
							(start 0.2032 0.3048)
							(mid 0.275042 0.275042)
							(end 0.3048 0.2032)
						)
					)
					(width 0)
					(fill yes)
				)
			)
		)
	)
	(footprint ""
		(layer "F.Cu")
		(at 273.939 -13.589 90)
		(property "Reference" "C2"
			(at 0 0 90)
			(layer "F.SilkS")
			(hide yes)
			(effects
				(font
					(size 1.27 1.27)
				)
			)
		)
		(property "Value" "SCD22U10V2KX-1GP"
			(at 1.1811 -2.7051 90)
			(unlocked yes)
			(layer "F.Fab")
			(hide yes)
			(effects
				(font
					(size 1.016 1.016)
					(thickness 0.1524)
				)
			)
		)
		(property "Device Type" "C402H22"
			(at 1.1811 -4.2291 90)
			(unlocked yes)
			(layer "F.Fab")
			(hide yes)
			(effects
				(font
					(size 1.016 1.016)
					(thickness 0.1524)
				)
			)
		)
		(duplicate_pad_numbers_are_jumpers no)
		(fp_rect
			(start -0.4318 0.9525)
			(end 0.4318 -0.9525)
			(stroke
				(width 0)
				(type default)
			)
			(fill no)
			(layer "F.CrtYd")
		)
		(fp_rect
			(start -0.4318 0.9525)
			(end 0.4318 -0.9525)
			(stroke
				(width 0)
				(type default)
			)
			(fill no)
			(layer "F.Fab")
		)
		(pad "1" smd custom
			(at 0 -0.4445 90)
			(size 0.1524 0.1524)
			(layers "F.Cu" "F.Mask" "F.Paste")
			(net "PCIE_TX_CAP_P0")
			(options
				(clearance outline)
				(anchor circle)
			)
			(primitives
				(gr_poly
					(pts
						(arc
							(start 0.3048 -0.2032)
							(mid 0.275042 -0.275042)
							(end 0.2032 -0.3048)
						)
						(arc
							(start -0.2032 -0.3048)
							(mid -0.275042 -0.275042)
							(end -0.3048 -0.2032)
						)
						(arc
							(start -0.3048 0.2032)
							(mid -0.275042 0.275042)
							(end -0.2032 0.3048)
						)
						(arc
							(start 0.2032 0.3048)
							(mid 0.275042 0.275042)
							(end 0.3048 0.2032)
						)
					)
					(width 0)
					(fill yes)
				)
			)
		)
		(pad "2" smd custom
			(at 0 0.4445 90)
			(size 0.1524 0.1524)
			(layers "F.Cu" "F.Mask" "F.Paste")
			(net "PCIE_TX_P0")
			(options
				(clearance outline)
				(anchor circle)
			)
			(primitives
				(gr_poly
					(pts
						(arc
							(start 0.3048 -0.2032)
							(mid 0.275042 -0.275042)
							(end 0.2032 -0.3048)
						)
						(arc
							(start -0.2032 -0.3048)
							(mid -0.275042 -0.275042)
							(end -0.3048 -0.2032)
						)
						(arc
							(start -0.3048 0.2032)
							(mid -0.275042 0.275042)
							(end -0.2032 0.3048)
						)
						(arc
							(start 0.2032 0.3048)
							(mid 0.275042 0.275042)
							(end 0.3048 0.2032)
						)
					)
					(width 0)
					(fill yes)
				)
			)
		)
	)
	(footprint ""
		(layer "F.Cu")
		(at 219.329 -10.16 -90)
		(property "Reference" "R657"
			(at 0 0 270)
			(layer "F.SilkS")
			(hide yes)
			(effects
				(font
					(size 1.27 1.27)
				)
			)
		)
		(property "Value" "100KR2F-L1-GP"
			(at 0.064008 -3.993896 270)
			(unlocked yes)
			(layer "F.Fab")
			(hide yes)
			(effects
				(font
					(size 1.016 1.016)
					(thickness 0.1524)
				)
			)
		)
		(property "Device Type" "R402H16"
			(at 0.064008 -5.517896 270)
			(unlocked yes)
			(layer "F.Fab")
			(hide yes)
			(effects
				(font
					(size 1.016 1.016)
					(thickness 0.1524)
				)
			)
		)
		(duplicate_pad_numbers_are_jumpers no)
		(fp_line
			(start -0.508 -0.9398)
			(end -0.508 0.9398)
			(stroke
				(width 0.1524)
				(type default)
			)
			(layer "F.SilkS")
		)
		(fp_line
			(start 0.508 -0.9398)
			(end -0.508 -0.9398)
			(stroke
				(width 0.1524)
				(type default)
			)
			(layer "F.SilkS")
		)
		(fp_rect
			(start -0.508 0.9398)
			(end 0.508 -0.9398)
			(stroke
				(width 0)
				(type default)
			)
			(fill no)
			(layer "F.CrtYd")
		)
		(fp_rect
			(start -0.508 0.9398)
			(end 0.508 -0.9398)
			(stroke
				(width 0)
				(type default)
			)
			(fill no)
			(layer "F.Fab")
		)
		(pad "1" smd custom
			(at 0 -0.4445 270)
			(size 0.1397 0.1397)
			(layers "F.Cu" "F.Mask" "F.Paste")
			(net "EEPROM_A1")
			(options
				(clearance outline)
				(anchor circle)
			)
			(primitives
				(gr_poly
					(pts
						(arc
							(start -0.1778 -0.2794)
							(mid -0.249642 -0.249642)
							(end -0.2794 -0.1778)
						)
						(arc
							(start -0.2794 0.1778)
							(mid -0.249642 0.249642)
							(end -0.1778 0.2794)
						)
						(arc
							(start 0.1778 0.2794)
							(mid 0.249642 0.249642)
							(end 0.2794 0.1778)
						)
						(arc
							(start 0.2794 -0.1778)
							(mid 0.249642 -0.249642)
							(end 0.1778 -0.2794)
						)
					)
					(width 0)
					(fill yes)
				)
			)
		)
		(pad "2" smd custom
			(at 0 0.4445 270)
			(size 0.1397 0.1397)
			(layers "F.Cu" "F.Mask" "F.Paste")
			(net "GND")
			(options
				(clearance outline)
				(anchor circle)
			)
			(primitives
				(gr_poly
					(pts
						(arc
							(start -0.1778 -0.2794)
							(mid -0.249642 -0.249642)
							(end -0.2794 -0.1778)
						)
						(arc
							(start -0.2794 0.1778)
							(mid -0.249642 0.249642)
							(end -0.1778 0.2794)
						)
						(arc
							(start 0.1778 0.2794)
							(mid 0.249642 0.249642)
							(end 0.2794 0.1778)
						)
						(arc
							(start 0.2794 -0.1778)
							(mid 0.249642 -0.249642)
							(end 0.1778 -0.2794)
						)
					)
					(width 0)
					(fill yes)
				)
			)
		)
	)
	(footprint ""
		(layer "F.Cu")
		(at 217.781124 -203.047092)
		(property "Reference" "R7918"
			(at 0 0 0)
			(layer "F.SilkS")
			(hide yes)
			(effects
				(font
					(size 1.27 1.27)
				)
			)
		)
		(property "Value" "0R2J-2-GP"
			(at 0.064008 -3.993896 0)
			(unlocked yes)
			(layer "F.Fab")
			(hide yes)
			(effects
				(font
					(size 1.016 1.016)
					(thickness 0.1524)
				)
			)
		)
		(property "Device Type" "R402H16"
			(at 0.064008 -5.517896 0)
			(unlocked yes)
			(layer "F.Fab")
			(hide yes)
			(effects
				(font
					(size 1.016 1.016)
					(thickness 0.1524)
				)
			)
		)
		(duplicate_pad_numbers_are_jumpers no)
		(fp_line
			(start -0.508 -0.9398)
			(end -0.508 0.9398)
			(stroke
				(width 0.1524)
				(type default)
			)
			(layer "F.SilkS")
		)
		(fp_line
			(start 0.508 -0.9398)
			(end -0.508 -0.9398)
			(stroke
				(width 0.1524)
				(type default)
			)
			(layer "F.SilkS")
		)
		(fp_rect
			(start -0.508 0.9398)
			(end 0.508 -0.9398)
			(stroke
				(width 0)
				(type default)
			)
			(fill no)
			(layer "F.CrtYd")
		)
		(fp_rect
			(start -0.508 0.9398)
			(end 0.508 -0.9398)
			(stroke
				(width 0)
				(type default)
			)
			(fill no)
			(layer "F.Fab")
		)
		(pad "1" smd custom
			(at 0 -0.4445)
			(size 0.1397 0.1397)
			(layers "F.Cu" "F.Mask" "F.Paste")
			(net "TWI_SDA1")
			(options
				(clearance outline)
				(anchor circle)
			)
			(primitives
				(gr_poly
					(pts
						(arc
							(start -0.1778 -0.2794)
							(mid -0.249642 -0.249642)
							(end -0.2794 -0.1778)
						)
						(arc
							(start -0.2794 0.1778)
							(mid -0.249642 0.249642)
							(end -0.1778 0.2794)
						)
						(arc
							(start 0.1778 0.2794)
							(mid 0.249642 0.249642)
							(end 0.2794 0.1778)
						)
						(arc
							(start 0.2794 -0.1778)
							(mid 0.249642 -0.249642)
							(end 0.1778 -0.2794)
						)
					)
					(width 0)
					(fill yes)
				)
			)
		)
		(pad "2" smd custom
			(at 0 0.4445)
			(size 0.1397 0.1397)
			(layers "F.Cu" "F.Mask" "F.Paste")
			(net "I2C_GPIO_SDA_3")
			(options
				(clearance outline)
				(anchor circle)
			)
			(primitives
				(gr_poly
					(pts
						(arc
							(start -0.1778 -0.2794)
							(mid -0.249642 -0.249642)
							(end -0.2794 -0.1778)
						)
						(arc
							(start -0.2794 0.1778)
							(mid -0.249642 0.249642)
							(end -0.1778 0.2794)
						)
						(arc
							(start 0.1778 0.2794)
							(mid 0.249642 0.249642)
							(end 0.2794 0.1778)
						)
						(arc
							(start 0.2794 -0.1778)
							(mid 0.249642 -0.249642)
							(end 0.1778 -0.2794)
						)
					)
					(width 0)
					(fill yes)
				)
			)
		)
	)
	(footprint ""
		(layer "F.Cu")
		(at 310.007 -58.6486)
		(property "Reference" "PG47"
			(at 0 0 0)
			(layer "F.SilkS")
			(hide yes)
			(effects
				(font
					(size 1.27 1.27)
				)
			)
		)
		(property "Value" "GAP-CLOSE-PWR-3-GP"
			(at 0.0254 -6.5786 0)
			(unlocked yes)
			(layer "F.Fab")
			(hide yes)
			(effects
				(font
					(size 1.016 1.016)
					(thickness 0.1524)
				)
			)
		)
		(property "Device Type" "GAP-CLOSE-PWR-3"
			(at 0.0254 -8.255 0)
			(unlocked yes)
			(layer "F.Fab")
			(hide yes)
			(effects
				(font
					(size 1.016 1.016)
					(thickness 0.1524)
				)
			)
		)
		(duplicate_pad_numbers_are_jumpers no)
		(fp_rect
			(start -0.7112 0.4572)
			(end 0.7112 -0.4572)
			(stroke
				(width 0)
				(type default)
			)
			(fill no)
			(layer "F.CrtYd")
		)
		(fp_poly
			(pts
				(xy -0.7112 -0.4572) (xy 0.7112 -0.4572) (xy 0.7112 0.4572) (xy -0.7112 0.4572)
			)
			(stroke
				(width 0)
				(type default)
			)
			(fill no)
			(layer "F.Fab")
		)
		(pad "1" smd rect
			(at -0.3048 0)
			(size 0.6604 0.762)
			(layers "F.Cu" "F.Mask" "F.Paste")
			(net "DUT_VDD")
		)
		(pad "2" smd rect
			(at 0.3048 0)
			(size 0.6604 0.762)
			(layers "F.Cu" "F.Mask" "F.Paste")
			(net "P0V9_E")
		)
	)
	(footprint ""
		(layer "F.Cu")
		(at 36.829492 -106.757724 -90)
		(property "Reference" "R417"
			(at 0 0 270)
			(layer "F.SilkS")
			(hide yes)
			(effects
				(font
					(size 1.27 1.27)
				)
			)
		)
		(property "Value" "10KR2F-2-GP"
			(at 0.064008 -3.993896 270)
			(unlocked yes)
			(layer "F.Fab")
			(hide yes)
			(effects
				(font
					(size 1.016 1.016)
					(thickness 0.1524)
				)
			)
		)
		(property "Device Type" "R402H16"
			(at 0.064008 -5.517896 270)
			(unlocked yes)
			(layer "F.Fab")
			(hide yes)
			(effects
				(font
					(size 1.016 1.016)
					(thickness 0.1524)
				)
			)
		)
		(duplicate_pad_numbers_are_jumpers no)
		(fp_line
			(start -0.508 -0.9398)
			(end -0.508 0.9398)
			(stroke
				(width 0.1524)
				(type default)
			)
			(layer "F.SilkS")
		)
		(fp_line
			(start 0.508 -0.9398)
			(end -0.508 -0.9398)
			(stroke
				(width 0.1524)
				(type default)
			)
			(layer "F.SilkS")
		)
		(fp_rect
			(start -0.508 0.9398)
			(end 0.508 -0.9398)
			(stroke
				(width 0)
				(type default)
			)
			(fill no)
			(layer "F.CrtYd")
		)
		(fp_rect
			(start -0.508 0.9398)
			(end 0.508 -0.9398)
			(stroke
				(width 0)
				(type default)
			)
			(fill no)
			(layer "F.Fab")
		)
		(pad "1" smd custom
			(at 0 -0.4445 270)
			(size 0.1397 0.1397)
			(layers "F.Cu" "F.Mask" "F.Paste")
			(net "GND")
			(options
				(clearance outline)
				(anchor circle)
			)
			(primitives
				(gr_poly
					(pts
						(arc
							(start -0.1778 -0.2794)
							(mid -0.249642 -0.249642)
							(end -0.2794 -0.1778)
						)
						(arc
							(start -0.2794 0.1778)
							(mid -0.249642 0.249642)
							(end -0.1778 0.2794)
						)
						(arc
							(start 0.1778 0.2794)
							(mid 0.249642 0.249642)
							(end 0.2794 0.1778)
						)
						(arc
							(start 0.2794 -0.1778)
							(mid 0.249642 -0.249642)
							(end 0.1778 -0.2794)
						)
					)
					(width 0)
					(fill yes)
				)
			)
		)
		(pad "2" smd custom
			(at 0 0.4445 270)
			(size 0.1397 0.1397)
			(layers "F.Cu" "F.Mask" "F.Paste")
			(net "RMII0_PHY_BMC_RXCTL0")
			(options
				(clearance outline)
				(anchor circle)
			)
			(primitives
				(gr_poly
					(pts
						(arc
							(start -0.1778 -0.2794)
							(mid -0.249642 -0.249642)
							(end -0.2794 -0.1778)
						)
						(arc
							(start -0.2794 0.1778)
							(mid -0.249642 0.249642)
							(end -0.1778 0.2794)
						)
						(arc
							(start 0.1778 0.2794)
							(mid 0.249642 0.249642)
							(end 0.2794 0.1778)
						)
						(arc
							(start 0.2794 -0.1778)
							(mid 0.249642 -0.249642)
							(end 0.1778 -0.2794)
						)
					)
					(width 0)
					(fill yes)
				)
			)
		)
	)
)
